(kicad_pcb
	(version 20260206)
	(generator "pcbnew")
	(generator_version "10.0")
	(general
		(thickness 1.6)
		(legacy_teardrops no)
	)
	(paper "A4")
	(title_block
		(title "panther-plus-userver — 13130-1b_20150205.brd")
		(comment 1 "Honey Badger (Wiwynn) / footprints 782-789 of 1509")
	)
	(layers
		(0 "F.Cu" signal "TOP")
		(4 "In1.Cu" signal "L2")
		(6 "In2.Cu" signal "L3")
		(8 "In3.Cu" signal "L4")
		(10 "In4.Cu" signal "L5")
		(12 "In5.Cu" signal "L6")
		(14 "In6.Cu" signal "L7")
		(16 "In7.Cu" signal "L8")
		(18 "In8.Cu" signal "L9")
		(20 "In9.Cu" signal "L10")
		(22 "In10.Cu" signal "L11")
		(2 "B.Cu" signal "BOTTOM")
		(9 "F.Adhes" user "F.Adhesive")
		(11 "B.Adhes" user "B.Adhesive")
		(13 "F.Paste" user "Package Geometry/Pastemask Top")
		(15 "B.Paste" user "Package Geometry/Pastemask Bottom")
		(5 "F.SilkS" user "Ref Des/Silkscreen Top")
		(7 "B.SilkS" user "Ref Des/Silkscreen Bottom")
		(1 "F.Mask" user "Board Geometry/Soldermask Top")
		(3 "B.Mask" user "Board Geometry/Soldermask Bottom")
		(17 "Dwgs.User" user "User.Drawings")
		(19 "Cmts.User" user "User.Comments")
		(21 "Eco1.User" user "User.Eco1")
		(23 "Eco2.User" user "User.Eco2")
		(25 "Edge.Cuts" user "Board Geometry/Outline")
		(27 "Margin" user)
		(31 "F.CrtYd" user "Package Geometry/Place Bound Top")
		(29 "B.CrtYd" user "Package Geometry/Place Bound Bottom")
		(35 "F.Fab" user "Ref Des/Assembly Top")
		(33 "B.Fab" user "Ref Des/Assembly Bottom")
	)
	(footprint ""
		(layer "F.Cu")
		(at 155.702 -28.956 180)
		(property "Reference" "R140"
			(at 0 0 180)
			(layer "F.SilkS")
			(hide yes)
			(effects
				(font
					(size 1.27 1.27)
				)
			)
		)
		(property "Value" "4K7R2F-GP"
			(at 0.064008 -3.993896 180)
			(unlocked yes)
			(layer "F.Fab")
			(hide yes)
			(effects
				(font
					(size 1.016 1.016)
					(thickness 0.1524)
				)
			)
		)
		(property "Device Type" "R402H16"
			(at 0.064008 -5.517896 180)
			(unlocked yes)
			(layer "F.Fab")
			(hide yes)
			(effects
				(font
					(size 1.016 1.016)
					(thickness 0.1524)
				)
			)
		)
		(duplicate_pad_numbers_are_jumpers no)
		(fp_rect
			(start -0.381 0.8382)
			(end 0.381 -0.8382)
			(stroke
				(width 0)
				(type default)
			)
			(fill no)
			(layer "F.CrtYd")
		)
		(fp_rect
			(start -0.381 0.8382)
			(end 0.381 -0.8382)
			(stroke
				(width 0)
				(type default)
			)
			(fill no)
			(layer "F.Fab")
		)
		(pad "1" smd custom
			(at 0 -0.4318 180)
			(size 0.127 0.127)
			(layers "F.Cu" "F.Mask" "F.Paste")
			(net "P3V3_STBY")
			(options
				(clearance outline)
				(anchor circle)
			)
			(primitives
				(gr_poly
					(pts
						(arc
							(start -0.2032 -0.2794)
							(mid -0.239121 -0.264521)
							(end -0.254 -0.2286)
						)
						(arc
							(start -0.254 0.2286)
							(mid -0.239121 0.264521)
							(end -0.2032 0.2794)
						)
						(arc
							(start 0.2032 0.2794)
							(mid 0.239121 0.264521)
							(end 0.254 0.2286)
						)
						(arc
							(start 0.254 -0.2286)
							(mid 0.239121 -0.264521)
							(end 0.2032 -0.2794)
						)
					)
					(width 0)
					(fill yes)
				)
			)
		)
		(pad "2" smd custom
			(at 0 0.4318 180)
			(size 0.127 0.127)
			(layers "F.Cu" "F.Mask" "F.Paste")
			(net "FPGA_SMB_HOST_CLK")
			(options
				(clearance outline)
				(anchor circle)
			)
			(primitives
				(gr_poly
					(pts
						(arc
							(start -0.2032 -0.2794)
							(mid -0.239121 -0.264521)
							(end -0.254 -0.2286)
						)
						(arc
							(start -0.254 0.2286)
							(mid -0.239121 0.264521)
							(end -0.2032 0.2794)
						)
						(arc
							(start 0.2032 0.2794)
							(mid 0.239121 0.264521)
							(end 0.254 0.2286)
						)
						(arc
							(start 0.254 -0.2286)
							(mid 0.239121 -0.264521)
							(end 0.2032 -0.2794)
						)
					)
					(width 0)
					(fill yes)
				)
			)
		)
	)
	(footprint ""
		(layer "F.Cu")
		(at 13.335 -60.071 180)
		(property "Reference" "PR49"
			(at 0 0 180)
			(layer "F.SilkS")
			(hide yes)
			(effects
				(font
					(size 1.27 1.27)
				)
			)
		)
		(property "Value" "0R2J-2-GP"
			(at 1.7907 -1.1176 180)
			(unlocked yes)
			(layer "F.Fab")
			(hide yes)
			(effects
				(font
					(size 1.016 1.016)
					(thickness 0.1524)
				)
			)
		)
		(property "Device Type" "R402H16"
			(at 1.7907 -2.6416 180)
			(unlocked yes)
			(layer "F.Fab")
			(hide yes)
			(effects
				(font
					(size 1.016 1.016)
					(thickness 0.1524)
				)
			)
		)
		(duplicate_pad_numbers_are_jumpers no)
		(fp_rect
			(start -0.381 0.8382)
			(end 0.381 -0.8382)
			(stroke
				(width 0)
				(type default)
			)
			(fill no)
			(layer "F.CrtYd")
		)
		(fp_rect
			(start -0.381 0.8382)
			(end 0.381 -0.8382)
			(stroke
				(width 0)
				(type default)
			)
			(fill no)
			(layer "F.Fab")
		)
		(pad "1" smd custom
			(at 0 -0.4318 180)
			(size 0.127 0.127)
			(layers "F.Cu" "F.Mask" "F.Paste")
			(net "TP_PVCCP_CLK")
			(options
				(clearance outline)
				(anchor circle)
			)
			(primitives
				(gr_poly
					(pts
						(arc
							(start -0.2032 -0.2794)
							(mid -0.239121 -0.264521)
							(end -0.254 -0.2286)
						)
						(arc
							(start -0.254 0.2286)
							(mid -0.239121 0.264521)
							(end -0.2032 0.2794)
						)
						(arc
							(start 0.2032 0.2794)
							(mid 0.239121 0.264521)
							(end 0.254 0.2286)
						)
						(arc
							(start 0.254 -0.2286)
							(mid 0.239121 -0.264521)
							(end 0.2032 -0.2794)
						)
					)
					(width 0)
					(fill yes)
				)
			)
		)
		(pad "2" smd custom
			(at 0 0.4318 180)
			(size 0.127 0.127)
			(layers "F.Cu" "F.Mask" "F.Paste")
			(net "SVID_CPU_CLK")
			(options
				(clearance outline)
				(anchor circle)
			)
			(primitives
				(gr_poly
					(pts
						(arc
							(start -0.2032 -0.2794)
							(mid -0.239121 -0.264521)
							(end -0.254 -0.2286)
						)
						(arc
							(start -0.254 0.2286)
							(mid -0.239121 0.264521)
							(end -0.2032 0.2794)
						)
						(arc
							(start 0.2032 0.2794)
							(mid 0.239121 0.264521)
							(end 0.254 0.2286)
						)
						(arc
							(start 0.254 -0.2286)
							(mid 0.239121 -0.264521)
							(end 0.2032 -0.2794)
						)
					)
					(width 0)
					(fill yes)
				)
			)
		)
	)
	(footprint ""
		(layer "F.Cu")
		(at 136.525 -15.113)
		(property "Reference" "C323"
			(at 0 0 0)
			(layer "F.SilkS")
			(hide yes)
			(effects
				(font
					(size 1.27 1.27)
				)
			)
		)
		(property "Value" "SCD1U10V2KX-5GP"
			(at 1.8923 -1.2065 0)
			(unlocked yes)
			(layer "F.Fab")
			(hide yes)
			(effects
				(font
					(size 1.016 1.016)
					(thickness 0.1524)
				)
			)
		)
		(property "Device Type" "C402H22"
			(at 1.8923 -2.7305 0)
			(unlocked yes)
			(layer "F.Fab")
			(hide yes)
			(effects
				(font
					(size 1.016 1.016)
					(thickness 0.1524)
				)
			)
		)
		(duplicate_pad_numbers_are_jumpers no)
		(fp_rect
			(start -0.381 0.7366)
			(end 0.381 -0.7366)
			(stroke
				(width 0)
				(type default)
			)
			(fill no)
			(layer "F.CrtYd")
		)
		(fp_rect
			(start -0.381 0.7366)
			(end 0.381 -0.7366)
			(stroke
				(width 0)
				(type default)
			)
			(fill no)
			(layer "F.Fab")
		)
		(pad "1" smd custom
			(at 0 -0.4572)
			(size 0.1143 0.1143)
			(layers "F.Cu" "F.Mask" "F.Paste")
			(net "HOST_LV_D_RSTBTN#")
			(options
				(clearance outline)
				(anchor circle)
			)
			(primitives
				(gr_poly
					(pts
						(arc
							(start -0.254 -0.1778)
							(mid -0.239121 -0.213721)
							(end -0.2032 -0.2286)
						)
						(arc
							(start 0.2032 -0.2286)
							(mid 0.239121 -0.213721)
							(end 0.254 -0.1778)
						)
						(arc
							(start 0.254 0.1778)
							(mid 0.239121 0.213721)
							(end 0.2032 0.2286)
						)
						(arc
							(start -0.2032 0.2286)
							(mid -0.239121 0.213721)
							(end -0.254 0.1778)
						)
					)
					(width 0)
					(fill yes)
				)
			)
		)
		(pad "2" smd custom
			(at 0 0.4572)
			(size 0.1143 0.1143)
			(layers "F.Cu" "F.Mask" "F.Paste")
			(net "GND")
			(options
				(clearance outline)
				(anchor circle)
			)
			(primitives
				(gr_poly
					(pts
						(arc
							(start -0.254 -0.1778)
							(mid -0.239121 -0.213721)
							(end -0.2032 -0.2286)
						)
						(arc
							(start 0.2032 -0.2286)
							(mid 0.239121 -0.213721)
							(end 0.254 -0.1778)
						)
						(arc
							(start 0.254 0.1778)
							(mid 0.239121 0.213721)
							(end 0.2032 0.2286)
						)
						(arc
							(start -0.2032 0.2286)
							(mid -0.239121 0.213721)
							(end -0.254 0.1778)
						)
					)
					(width 0)
					(fill yes)
				)
			)
		)
	)
	(footprint ""
		(layer "F.Cu")
		(at 32.893 -20.193 180)
		(property "Reference" "R264"
			(at 0 0 180)
			(layer "F.SilkS")
			(hide yes)
			(effects
				(font
					(size 1.27 1.27)
				)
			)
		)
		(property "Value" "0R2J-2-GP"
			(at 0.064008 -3.993896 180)
			(unlocked yes)
			(layer "F.Fab")
			(hide yes)
			(effects
				(font
					(size 1.016 1.016)
					(thickness 0.1524)
				)
			)
		)
		(property "Device Type" "R402H16"
			(at 0.064008 -5.517896 180)
			(unlocked yes)
			(layer "F.Fab")
			(hide yes)
			(effects
				(font
					(size 1.016 1.016)
					(thickness 0.1524)
				)
			)
		)
		(duplicate_pad_numbers_are_jumpers no)
		(fp_rect
			(start -0.381 0.8382)
			(end 0.381 -0.8382)
			(stroke
				(width 0)
				(type default)
			)
			(fill no)
			(layer "F.CrtYd")
		)
		(fp_rect
			(start -0.381 0.8382)
			(end 0.381 -0.8382)
			(stroke
				(width 0)
				(type default)
			)
			(fill no)
			(layer "F.Fab")
		)
		(pad "1" smd custom
			(at 0 -0.4318 180)
			(size 0.127 0.127)
			(layers "F.Cu" "F.Mask" "F.Paste")
			(net "XDP_DFX_PORT_R_CLK1")
			(options
				(clearance outline)
				(anchor circle)
			)
			(primitives
				(gr_poly
					(pts
						(arc
							(start -0.2032 -0.2794)
							(mid -0.239121 -0.264521)
							(end -0.254 -0.2286)
						)
						(arc
							(start -0.254 0.2286)
							(mid -0.239121 0.264521)
							(end -0.2032 0.2794)
						)
						(arc
							(start 0.2032 0.2794)
							(mid 0.239121 0.264521)
							(end 0.254 0.2286)
						)
						(arc
							(start 0.254 -0.2286)
							(mid 0.239121 -0.264521)
							(end 0.2032 -0.2794)
						)
					)
					(width 0)
					(fill yes)
				)
			)
		)
		(pad "2" smd custom
			(at 0 0.4318 180)
			(size 0.127 0.127)
			(layers "F.Cu" "F.Mask" "F.Paste")
			(net "XDP_DFX_PORT_CLK1")
			(options
				(clearance outline)
				(anchor circle)
			)
			(primitives
				(gr_poly
					(pts
						(arc
							(start -0.2032 -0.2794)
							(mid -0.239121 -0.264521)
							(end -0.254 -0.2286)
						)
						(arc
							(start -0.254 0.2286)
							(mid -0.239121 0.264521)
							(end -0.2032 0.2794)
						)
						(arc
							(start 0.2032 0.2794)
							(mid 0.239121 0.264521)
							(end 0.254 0.2286)
						)
						(arc
							(start 0.254 -0.2286)
							(mid 0.239121 -0.264521)
							(end 0.2032 -0.2794)
						)
					)
					(width 0)
					(fill yes)
				)
			)
		)
	)
	(footprint ""
		(layer "F.Cu")
		(at 141.859 -49.403 180)
		(property "Reference" "TP41"
			(at 0 0 180)
			(layer "F.SilkS")
			(hide yes)
			(effects
				(font
					(size 1.27 1.27)
				)
			)
		)
		(property "Value" "TPAD32-GP"
			(at 0 -3.166364 180)
			(unlocked yes)
			(layer "F.Fab")
			(hide yes)
			(effects
				(font
					(size 1.016 1.016)
					(thickness 0.1524)
				)
			)
		)
		(property "Device Type" "TPAD32"
			(at 0 -4.690618 180)
			(unlocked yes)
			(layer "F.Fab")
			(hide yes)
			(effects
				(font
					(size 1.016 1.016)
					(thickness 0.1524)
				)
			)
		)
		(duplicate_pad_numbers_are_jumpers no)
		(fp_poly
			(pts
				(arc
					(start -0.7112 0)
					(mid 0.7112 0)
					(end -0.7112 0)
				)
			)
			(stroke
				(width 0)
				(type default)
			)
			(fill no)
			(layer "F.CrtYd")
		)
		(fp_poly
			(pts
				(arc
					(start -0.7112 0)
					(mid 0.7112 0)
					(end -0.7112 0)
				)
			)
			(stroke
				(width 0)
				(type default)
			)
			(fill no)
			(layer "F.Fab")
		)
		(pad "1" smd circle
			(at 0 0 180)
			(size 0.8128 0.8128)
			(layers "F.Cu" "F.Mask" "F.Paste")
			(net "C_NCONFIG#")
		)
	)
	(footprint ""
		(layer "F.Cu")
		(at 46.101 -19.177 90)
		(property "Reference" "C206"
			(at 0 0 90)
			(layer "F.SilkS")
			(hide yes)
			(effects
				(font
					(size 1.27 1.27)
				)
			)
		)
		(property "Value" "SCD1U10V2KX-5GP"
			(at 1.1811 -2.7051 90)
			(unlocked yes)
			(layer "F.Fab")
			(hide yes)
			(effects
				(font
					(size 1.016 1.016)
					(thickness 0.1524)
				)
			)
		)
		(property "Device Type" "C402H22"
			(at 1.1811 -4.2291 90)
			(unlocked yes)
			(layer "F.Fab")
			(hide yes)
			(effects
				(font
					(size 1.016 1.016)
					(thickness 0.1524)
				)
			)
		)
		(duplicate_pad_numbers_are_jumpers no)
		(fp_rect
			(start -0.381 0.7366)
			(end 0.381 -0.7366)
			(stroke
				(width 0)
				(type default)
			)
			(fill no)
			(layer "F.CrtYd")
		)
		(fp_rect
			(start -0.381 0.7366)
			(end 0.381 -0.7366)
			(stroke
				(width 0)
				(type default)
			)
			(fill no)
			(layer "F.Fab")
		)
		(pad "1" smd custom
			(at 0 -0.4572 90)
			(size 0.1143 0.1143)
			(layers "F.Cu" "F.Mask" "F.Paste")
			(net "P3V3_VDD_CLKBUFF")
			(options
				(clearance outline)
				(anchor circle)
			)
			(primitives
				(gr_poly
					(pts
						(arc
							(start -0.254 -0.1778)
							(mid -0.239121 -0.213721)
							(end -0.2032 -0.2286)
						)
						(arc
							(start 0.2032 -0.2286)
							(mid 0.239121 -0.213721)
							(end 0.254 -0.1778)
						)
						(arc
							(start 0.254 0.1778)
							(mid 0.239121 0.213721)
							(end 0.2032 0.2286)
						)
						(arc
							(start -0.2032 0.2286)
							(mid -0.239121 0.213721)
							(end -0.254 0.1778)
						)
					)
					(width 0)
					(fill yes)
				)
			)
		)
		(pad "2" smd custom
			(at 0 0.4572 90)
			(size 0.1143 0.1143)
			(layers "F.Cu" "F.Mask" "F.Paste")
			(net "GND")
			(options
				(clearance outline)
				(anchor circle)
			)
			(primitives
				(gr_poly
					(pts
						(arc
							(start -0.254 -0.1778)
							(mid -0.239121 -0.213721)
							(end -0.2032 -0.2286)
						)
						(arc
							(start 0.2032 -0.2286)
							(mid 0.239121 -0.213721)
							(end 0.254 -0.1778)
						)
						(arc
							(start 0.254 0.1778)
							(mid 0.239121 0.213721)
							(end 0.2032 0.2286)
						)
						(arc
							(start -0.2032 0.2286)
							(mid -0.239121 0.213721)
							(end -0.254 0.1778)
						)
					)
					(width 0)
					(fill yes)
				)
			)
		)
	)
	(footprint ""
		(layer "F.Cu")
		(at 56.515 -44.577)
		(property "Reference" "R54"
			(at 0 0 0)
			(layer "F.SilkS")
			(hide yes)
			(effects
				(font
					(size 1.27 1.27)
				)
			)
		)
		(property "Value" "0R2J-2-GP"
			(at 0.064008 -3.993896 0)
			(unlocked yes)
			(layer "F.Fab")
			(hide yes)
			(effects
				(font
					(size 1.016 1.016)
					(thickness 0.1524)
				)
			)
		)
		(property "Device Type" "R402H16"
			(at 0.064008 -5.517896 0)
			(unlocked yes)
			(layer "F.Fab")
			(hide yes)
			(effects
				(font
					(size 1.016 1.016)
					(thickness 0.1524)
				)
			)
		)
		(duplicate_pad_numbers_are_jumpers no)
		(fp_rect
			(start -0.381 0.8382)
			(end 0.381 -0.8382)
			(stroke
				(width 0)
				(type default)
			)
			(fill no)
			(layer "F.CrtYd")
		)
		(fp_rect
			(start -0.381 0.8382)
			(end 0.381 -0.8382)
			(stroke
				(width 0)
				(type default)
			)
			(fill no)
			(layer "F.Fab")
		)
		(pad "1" smd custom
			(at 0 -0.4318)
			(size 0.127 0.127)
			(layers "F.Cu" "F.Mask" "F.Paste")
			(net "PWRGD_P1V8_PG")
			(options
				(clearance outline)
				(anchor circle)
			)
			(primitives
				(gr_poly
					(pts
						(arc
							(start -0.2032 -0.2794)
							(mid -0.239121 -0.264521)
							(end -0.254 -0.2286)
						)
						(arc
							(start -0.254 0.2286)
							(mid -0.239121 0.264521)
							(end -0.2032 0.2794)
						)
						(arc
							(start 0.2032 0.2794)
							(mid 0.239121 0.264521)
							(end 0.254 0.2286)
						)
						(arc
							(start 0.254 -0.2286)
							(mid 0.239121 -0.264521)
							(end 0.2032 -0.2794)
						)
					)
					(width 0)
					(fill yes)
				)
			)
		)
		(pad "2" smd custom
			(at 0 0.4318)
			(size 0.127 0.127)
			(layers "F.Cu" "F.Mask" "F.Paste")
			(net "SW_P3V3_EN_G2")
			(options
				(clearance outline)
				(anchor circle)
			)
			(primitives
				(gr_poly
					(pts
						(arc
							(start -0.2032 -0.2794)
							(mid -0.239121 -0.264521)
							(end -0.254 -0.2286)
						)
						(arc
							(start -0.254 0.2286)
							(mid -0.239121 0.264521)
							(end -0.2032 0.2794)
						)
						(arc
							(start 0.2032 0.2794)
							(mid 0.239121 0.264521)
							(end 0.254 0.2286)
						)
						(arc
							(start 0.254 -0.2286)
							(mid 0.239121 -0.264521)
							(end 0.2032 -0.2794)
						)
					)
					(width 0)
					(fill yes)
				)
			)
		)
	)
	(footprint ""
		(layer "F.Cu")
		(at 177.165 -57.15)
		(property "Reference" "R173"
			(at 0 0 0)
			(layer "F.SilkS")
			(hide yes)
			(effects
				(font
					(size 1.27 1.27)
				)
			)
		)
		(property "Value" "4K7R2F-GP"
			(at 0.064008 -3.993896 0)
			(unlocked yes)
			(layer "F.Fab")
			(hide yes)
			(effects
				(font
					(size 1.016 1.016)
					(thickness 0.1524)
				)
			)
		)
		(property "Device Type" "R402H16"
			(at 0.064008 -5.517896 0)
			(unlocked yes)
			(layer "F.Fab")
			(hide yes)
			(effects
				(font
					(size 1.016 1.016)
					(thickness 0.1524)
				)
			)
		)
		(duplicate_pad_numbers_are_jumpers no)
		(fp_rect
			(start -0.381 0.8382)
			(end 0.381 -0.8382)
			(stroke
				(width 0)
				(type default)
			)
			(fill no)
			(layer "F.CrtYd")
		)
		(fp_rect
			(start -0.381 0.8382)
			(end 0.381 -0.8382)
			(stroke
				(width 0)
				(type default)
			)
			(fill no)
			(layer "F.Fab")
		)
		(pad "1" smd custom
			(at 0 -0.4318)
			(size 0.127 0.127)
			(layers "F.Cu" "F.Mask" "F.Paste")
			(net "P3V3_STBY")
			(options
				(clearance outline)
				(anchor circle)
			)
			(primitives
				(gr_poly
					(pts
						(arc
							(start -0.2032 -0.2794)
							(mid -0.239121 -0.264521)
							(end -0.254 -0.2286)
						)
						(arc
							(start -0.254 0.2286)
							(mid -0.239121 0.264521)
							(end -0.2032 0.2794)
						)
						(arc
							(start 0.2032 0.2794)
							(mid 0.239121 0.264521)
							(end 0.254 0.2286)
						)
						(arc
							(start 0.254 -0.2286)
							(mid 0.239121 -0.264521)
							(end 0.2032 -0.2794)
						)
					)
					(width 0)
					(fill yes)
				)
			)
		)
		(pad "2" smd custom
			(at 0 0.4318)
			(size 0.127 0.127)
			(layers "F.Cu" "F.Mask" "F.Paste")
			(net "EEPROM_A0")
			(options
				(clearance outline)
				(anchor circle)
			)
			(primitives
				(gr_poly
					(pts
						(arc
							(start -0.2032 -0.2794)
							(mid -0.239121 -0.264521)
							(end -0.254 -0.2286)
						)
						(arc
							(start -0.254 0.2286)
							(mid -0.239121 0.264521)
							(end -0.2032 0.2794)
						)
						(arc
							(start 0.2032 0.2794)
							(mid 0.239121 0.264521)
							(end 0.254 0.2286)
						)
						(arc
							(start 0.254 -0.2286)
							(mid 0.239121 -0.264521)
							(end 0.2032 -0.2794)
						)
					)
					(width 0)
					(fill yes)
				)
			)
		)
	)
)
